# TIMECARD (Time Appliance Project (Time Card)) — schematic netlist excerpt (pin names and nets, part order shuffled) for the footprints in the layout excerpt that follows; sources: Cadence DE-HDL packaged netlist, KiCad conversion of R4006-B0001-02_R01.brd

R458  RESISTOR  1KOHM 1%  pkg SMC_0402R_H016  page 24 : \1\ = SG ; \2\ = MUX2_SEL
C106  CAPACITOR  0.1UF 10V 10%  pkg SMC_0402R_H022  page 14 : \1\ = XP1R8V_FPGA_VCCAUX ; \2\ = SG

(kicad_pcb
	(version 20260206)
	(generator "pcbnew")
	(generator_version "10.0")
	(general
		(thickness 1.6)
		(legacy_teardrops no)
	)
	(paper "A4")
	(title_block
		(title "timecard-production-celestica-r4006 — R4006-B0001-02_R01.brd")
		(comment 1 "Time Appliance Project (Time Card) / footprints 758-759 of 1113")
	)
	(layers
		(0 "F.Cu" signal "TOP")
		(4 "In1.Cu" signal "L02_GND1")
		(6 "In2.Cu" signal "L03_SIG1")
		(8 "In3.Cu" signal "L04_GND2")
		(10 "In4.Cu" signal "L05_VCC1")
		(12 "In5.Cu" signal "L06_VCC2")
		(14 "In6.Cu" signal "L07_GND3")
		(16 "In7.Cu" signal "L08_SIG2")
		(18 "In8.Cu" signal "L09_GND4")
		(2 "B.Cu" signal "BOTTOM")
		(9 "F.Adhes" user "F.Adhesive")
		(11 "B.Adhes" user "B.Adhesive")
		(13 "F.Paste" user "Package Geometry/Pastemask Top")
		(15 "B.Paste" user "Package Geometry/Pastemask Bottom")
		(5 "F.SilkS" user "Ref Des/Silkscreen Top")
		(7 "B.SilkS" user "Ref Des/Silkscreen Bottom")
		(1 "F.Mask" user "Board Geometry/Soldermask Top")
		(3 "B.Mask" user "Board Geometry/Soldermask Bottom")
		(17 "Dwgs.User" user "User.Drawings")
		(19 "Cmts.User" user "User.Comments")
		(21 "Eco1.User" user "User.Eco1")
		(23 "Eco2.User" user "User.Eco2")
		(25 "Edge.Cuts" user "Board Geometry/Outline")
		(27 "Margin" user)
		(31 "F.CrtYd" user "Package Geometry/Place Bound Top")
		(29 "B.CrtYd" user "Package Geometry/Place Bound Bottom")
		(35 "F.Fab" user "Ref Des/Assembly Top")
		(33 "B.Fab" user "Ref Des/Assembly Bottom")
	)
	(footprint ""
		(layer "B.Cu")
		(at 101.4476 -82.2706 180)
		(property "Reference" "R458"
			(at -0.0254 -1.66497 0)
			(unlocked yes)
			(layer "B.SilkS")
			(effects
				(font
					(size 0.7874 0.5842)
					(thickness 0.1524)
				)
				(justify mirror)
			)
		)
		(property "Value" "VAL*"
			(at -0.02032 2.13233 180)
			(unlocked yes)
			(layer "B.Fab")
			(hide yes)
			(effects
				(font
					(size 0.7874 0.5842)
					(thickness 0.1524)
				)
				(justify mirror)
			)
		)
		(property "Tolerance" "TOL*"
			(at -0.044704 3.05435 180)
			(unlocked yes)
			(layer "Cmts.User")
			(hide yes)
			(effects
				(font
					(size 0.7874 0.5842)
					(thickness 0.1524)
				)
				(justify mirror)
			)
		)
		(property "User Part Number" "PARTNUM*"
			(at -0.02032 4.024884 180)
			(unlocked yes)
			(layer "Cmts.User")
			(hide yes)
			(effects
				(font
					(size 0.7874 0.5842)
					(thickness 0.1524)
				)
				(justify mirror)
			)
		)
		(property "Device Type" "RESISTOR-G155-11001-01,1KOHM,1%"
			(at -0.008382 1.210564 180)
			(unlocked yes)
			(layer "B.Fab")
			(hide yes)
			(effects
				(font
					(size 0.7874 0.5842)
					(thickness 0.1524)
				)
				(justify mirror)
			)
		)
		(duplicate_pad_numbers_are_jumpers no)
		(fp_line
			(start 1.143 0.5588)
			(end -1.143 0.5588)
			(stroke
				(width 0.1)
				(type default)
			)
			(layer "B.SilkS")
		)
		(fp_line
			(start 1.143 -0.5588)
			(end 1.143 0.5588)
			(stroke
				(width 0.1)
				(type default)
			)
			(layer "B.SilkS")
		)
		(fp_line
			(start -1.143 0.5588)
			(end -1.143 -0.5588)
			(stroke
				(width 0.1)
				(type default)
			)
			(layer "B.SilkS")
		)
		(fp_line
			(start -1.143 -0.5588)
			(end 1.143 -0.5588)
			(stroke
				(width 0.1)
				(type default)
			)
			(layer "B.SilkS")
		)
		(fp_poly
			(pts
				(xy 1.143 0.5588) (xy -1.143 0.5588) (xy -1.143 -0.5588) (xy 1.143 -0.5588)
			)
			(stroke
				(width 0)
				(type default)
			)
			(fill no)
			(layer "B.CrtYd")
		)
		(fp_line
			(start 0.508 0.3048)
			(end -0.508 0.3048)
			(stroke
				(width 0.1)
				(type default)
			)
			(layer "B.Fab")
		)
		(fp_line
			(start 0.508 -0.3048)
			(end 0.508 0.3048)
			(stroke
				(width 0.1)
				(type default)
			)
			(layer "B.Fab")
		)
		(fp_line
			(start -0.508 0.3048)
			(end -0.508 -0.3048)
			(stroke
				(width 0.1)
				(type default)
			)
			(layer "B.Fab")
		)
		(fp_line
			(start -0.508 -0.3048)
			(end 0.508 -0.3048)
			(stroke
				(width 0.1)
				(type default)
			)
			(layer "B.Fab")
		)
		(pad "1" smd rect
			(at 0.5334 0)
			(size 0.7112 0.6096)
			(layers "B.Cu" "B.Mask" "B.Paste")
			(net "SG")
		)
		(pad "2" smd rect
			(at -0.5334 0)
			(size 0.7112 0.6096)
			(layers "B.Cu" "B.Mask" "B.Paste")
			(net "MUX2_SEL")
		)
		(zone
			(layer "B.Cu")
			(hatch none 0.5)
			(connect_pads
				(clearance 0)
			)
			(min_thickness 0.25)
			(keepout
				(tracks not_allowed)
				(vias allowed)
				(pads allowed)
				(copperpour not_allowed)
				(footprints allowed)
			)
			(placement
				(enabled no)
				(sheetname "")
			)
			(fill
				(thermal_gap 0.5)
				(thermal_bridge_width 0.5)
				(island_removal_mode 0)
			)
			(polygon
				(pts
					(xy 101.3714 -82.5754) (xy 101.3714 -81.9658) (xy 101.5238 -81.9658) (xy 101.5238 -82.5754)
				)
			)
		)
		(zone
			(layer "B.Cu")
			(hatch none 0.5)
			(connect_pads
				(clearance 0)
			)
			(min_thickness 0.25)
			(keepout
				(tracks allowed)
				(vias not_allowed)
				(pads allowed)
				(copperpour not_allowed)
				(footprints allowed)
			)
			(placement
				(enabled no)
				(sheetname "")
			)
			(fill
				(thermal_gap 0.5)
				(thermal_bridge_width 0.5)
				(island_removal_mode 0)
			)
			(polygon
				(pts
					(xy 101.3714 -82.5754) (xy 101.3714 -81.9658) (xy 101.5238 -81.9658) (xy 101.5238 -82.5754)
				)
			)
		)
	)
	(footprint ""
		(layer "B.Cu")
		(at 102.347014 -45.823124)
		(property "Reference" "C106"
			(at 0.014986 1.150874 0)
			(unlocked yes)
			(layer "B.SilkS")
			(effects
				(font
					(size 0.635 0.4064)
					(thickness 0.1524)
				)
				(justify mirror)
			)
		)
		(property "Value" "VAL*"
			(at 0 3.718306 0)
			(unlocked yes)
			(layer "B.Fab")
			(hide yes)
			(effects
				(font
					(size 0.7874 0.5842)
					(thickness 0.127)
				)
				(justify mirror)
			)
		)
		(property "Tolerance" "TOL*"
			(at 0 4.861306 0)
			(unlocked yes)
			(layer "Cmts.User")
			(hide yes)
			(effects
				(font
					(size 0.7874 0.5842)
					(thickness 0.127)
				)
				(justify mirror)
			)
		)
		(property "User Part Number" "PARTNUM*"
			(at 0 2.575306 0)
			(unlocked yes)
			(layer "Cmts.User")
			(hide yes)
			(effects
				(font
					(size 0.7874 0.5842)
					(thickness 0.127)
				)
				(justify mirror)
			)
		)
		(property "Device Type" "CAPACITOR-G105-0B104-CK,0.1UF,A"
			(at 0 1.432306 0)
			(unlocked yes)
			(layer "B.Fab")
			(hide yes)
			(effects
				(font
					(size 0.7874 0.5842)
					(thickness 0.127)
				)
				(justify mirror)
			)
		)
		(duplicate_pad_numbers_are_jumpers no)
		(fp_line
			(start -0.970026 -0.4699)
			(end -0.970026 0.4699)
			(stroke
				(width 0.1)
				(type default)
			)
			(layer "B.SilkS")
		)
		(fp_line
			(start -0.970026 0.4699)
			(end 0.970026 0.4699)
			(stroke
				(width 0.1)
				(type default)
			)
			(layer "B.SilkS")
		)
		(fp_line
			(start 0.970026 -0.4699)
			(end -0.970026 -0.4699)
			(stroke
				(width 0.1)
				(type default)
			)
			(layer "B.SilkS")
		)
		(fp_line
			(start 0.970026 0.4699)
			(end 0.970026 -0.4699)
			(stroke
				(width 0.1)
				(type default)
			)
			(layer "B.SilkS")
		)
		(fp_poly
			(pts
				(xy 0.970026 0.4699) (xy -0.970026 0.4699) (xy -0.970026 -0.4699) (xy 0.970026 -0.4699)
			)
			(stroke
				(width 0)
				(type default)
			)
			(fill no)
			(layer "B.CrtYd")
		)
		(fp_line
			(start -0.508 -0.3048)
			(end -0.508 0.3048)
			(stroke
				(width 0.1)
				(type default)
			)
			(layer "B.Fab")
		)
		(fp_line
			(start -0.508 0.3048)
			(end 0.508 0.3048)
			(stroke
				(width 0.1)
				(type default)
			)
			(layer "B.Fab")
		)
		(fp_line
			(start 0.508 -0.3048)
			(end -0.508 -0.3048)
			(stroke
				(width 0.1)
				(type default)
			)
			(layer "B.Fab")
		)
		(fp_line
			(start 0.508 0.3048)
			(end 0.508 -0.3048)
			(stroke
				(width 0.1)
				(type default)
			)
			(layer "B.Fab")
		)
		(pad "1" smd circle
			(at 0.500126 0 180)
			(size 0.635 0.635)
			(layers "B.Cu" "B.Mask" "B.Paste")
			(net "XP1R8V_FPGA_VCCAUX")
		)
		(pad "2" smd circle
			(at -0.500126 0 180)
			(size 0.635 0.635)
			(layers "B.Cu" "B.Mask" "B.Paste")
			(net "SG")
		)
	)
)
